(kicad_sch
	(version 20250114)
	(generator "eeschema")
	(generator_version "9.0")
	(paper "A3")
	(title_block
		(title "OCuLink to 10GbE adapter")
		(date "2026-02-23")
		(rev "1.1.0")
		(company "Antmicro Ltd")
		(comment 1 "www.antmicro.com")
	)
	(text "Ideal Diode"
		(exclude_from_sim no)
		(at 200.406 127.254 0)
		(effects
			(font
				(size 2 2)
				(thickness 0.4)
				(bold yes)
			)
			(justify left bottom)
		)
	)
	(junction
		(at 226.06 149.86)
		(diameter 0)
		(color 0 0 0 0)
	)
	(junction
		(at 196.85 154.94)
		(diameter 0)
		(color 0 0 0 0)
	)
	(junction
		(at 187.96 137.16)
		(diameter 0)
		(color 0 0 0 0)
	)
	(junction
		(at 187.96 149.86)
		(diameter 0)
		(color 0 0 0 0)
	)
	(junction
		(at 196.85 160.02)
		(diameter 0)
		(color 0 0 0 0)
	)
	(junction
		(at 226.06 137.16)
		(diameter 0)
		(color 0 0 0 0)
	)
	(no_connect
		(at 217.17 154.94)
	)
	(wire
		(pts
			(xy 217.17 152.4) (xy 219.71 152.4)
		)
		(stroke
			(width 0)
			(type default)
		)
	)
	(wire
		(pts
			(xy 196.85 152.4) (xy 196.85 154.94)
		)
		(stroke
			(width 0)
			(type default)
		)
	)
	(wire
		(pts
			(xy 222.25 137.16) (xy 226.06 137.16)
		)
		(stroke
			(width 0)
			(type default)
		)
	)
	(wire
		(pts
			(xy 187.96 149.86) (xy 199.39 149.86)
		)
		(stroke
			(width 0)
			(type default)
		)
	)
	(wire
		(pts
			(xy 196.85 154.94) (xy 199.39 154.94)
		)
		(stroke
			(width 0)
			(type default)
		)
	)
	(wire
		(pts
			(xy 185.42 137.16) (xy 187.96 137.16)
		)
		(stroke
			(width 0)
			(type default)
		)
	)
	(wire
		(pts
			(xy 219.71 143.51) (xy 219.71 152.4)
		)
		(stroke
			(width 0)
			(type default)
		)
	)
	(wire
		(pts
			(xy 196.85 152.4) (xy 199.39 152.4)
		)
		(stroke
			(width 0)
			(type default)
		)
	)
	(wire
		(pts
			(xy 226.06 137.16) (xy 228.6 137.16)
		)
		(stroke
			(width 0)
			(type default)
		)
	)
	(wire
		(pts
			(xy 187.96 137.16) (xy 187.96 149.86)
		)
		(stroke
			(width 0)
			(type default)
		)
	)
	(wire
		(pts
			(xy 226.06 157.48) (xy 226.06 162.56)
		)
		(stroke
			(width 0)
			(type default)
		)
	)
	(wire
		(pts
			(xy 226.06 137.16) (xy 226.06 149.86)
		)
		(stroke
			(width 0)
			(type default)
		)
	)
	(wire
		(pts
			(xy 217.17 149.86) (xy 226.06 149.86)
		)
		(stroke
			(width 0)
			(type default)
		)
	)
	(wire
		(pts
			(xy 196.85 160.02) (xy 196.85 162.56)
		)
		(stroke
			(width 0)
			(type default)
		)
	)
	(wire
		(pts
			(xy 187.96 149.86) (xy 187.96 152.4)
		)
		(stroke
			(width 0)
			(type default)
		)
	)
	(wire
		(pts
			(xy 196.85 154.94) (xy 196.85 160.02)
		)
		(stroke
			(width 0)
			(type default)
		)
	)
	(wire
		(pts
			(xy 187.96 160.02) (xy 196.85 160.02)
		)
		(stroke
			(width 0)
			(type default)
		)
	)
	(wire
		(pts
			(xy 187.96 157.48) (xy 187.96 160.02)
		)
		(stroke
			(width 0)
			(type default)
		)
	)
	(wire
		(pts
			(xy 226.06 149.86) (xy 226.06 152.4)
		)
		(stroke
			(width 0)
			(type default)
		)
	)
	(wire
		(pts
			(xy 187.96 137.16) (xy 212.09 137.16)
		)
		(stroke
			(width 0)
			(type default)
		)
	)
	(hierarchical_label "VOUT"
		(shape output)
		(at 228.6 137.16 0)
		(effects
			(font
				(size 1.27 1.27)
			)
			(justify left)
		)
	)
	(hierarchical_label "VIN"
		(shape input)
		(at 185.42 137.16 180)
		(effects
			(font
				(size 1.27 1.27)
			)
			(justify right)
		)
	)
	(symbol
		(lib_id "antmicroCapacitors0402:C_1u_25V_0402")
		(at 226.06 157.48 90)
		(unit 1)
		(exclude_from_sim no)
		(in_bom yes)
		(on_board yes)
		(dnp no)
		(property "Reference" "C201"
			(at 228.346 153.67 90)
			(effects
				(font
					(size 1.27 1.27)
					(thickness 0.15)
				)
				(justify right)
			)
		)
		(property "Value" "C_1u_25V_0402"
			(at 236.22 137.16 0)
			(effects
				(font
					(size 1.27 1.27)
					(thickness 0.15)
				)
				(justify left bottom)
				(hide yes)
			)
		)
		(property "Footprint" "antmicro-footprints:C_0402_1005Metric"
			(at 238.76 137.16 0)
			(effects
				(font
					(size 1.27 1.27)
					(thickness 0.15)
				)
				(justify left bottom)
				(hide yes)
			)
		)
		(property "Datasheet" "https://www.murata.com/products/productdetail?partno=GRM155R61E105KE11%23"
			(at 241.3 137.16 0)
			(effects
				(font
					(size 1.27 1.27)
					(thickness 0.15)
				)
				(justify left bottom)
				(hide yes)
			)
		)
		(property "Description" "SMD Multilayer Ceramic Capacitor, 1 µF, 25 V, 0402 [1005 Metric], ± 10%, X5R, GRM Series"
			(at 226.06 157.48 0)
			(effects
				(font
					(size 1.27 1.27)
				)
				(hide yes)
			)
		)
		(property "MPN" "GRM155R61E105KE11J"
			(at 243.84 137.16 0)
			(effects
				(font
					(size 1.27 1.27)
					(thickness 0.15)
				)
				(justify left bottom)
				(hide yes)
			)
		)
		(property "Manufacturer" "Murata"
			(at 246.38 137.16 0)
			(effects
				(font
					(size 1.27 1.27)
					(thickness 0.15)
				)
				(justify left bottom)
				(hide yes)
			)
		)
		(property "License" "Apache-2.0"
			(at 248.92 137.16 0)
			(effects
				(font
					(size 1.27 1.27)
					(thickness 0.15)
				)
				(justify left bottom)
				(hide yes)
			)
		)
		(property "Author" "Antmicro"
			(at 251.46 137.16 0)
			(effects
				(font
					(size 1.27 1.27)
					(thickness 0.15)
				)
				(justify left bottom)
				(hide yes)
			)
		)
		(property "Val" "1u"
			(at 228.346 156.21 90)
			(effects
				(font
					(size 1.27 1.27)
					(thickness 0.15)
				)
				(justify right)
			)
		)
		(property "Voltage" "25V"
			(at 254 137.16 0)
			(effects
				(font
					(size 1.27 1.27)
				)
				(justify left bottom)
				(hide yes)
			)
		)
		(property "Dielectric" "X5R"
			(at 256.54 137.16 0)
			(effects
				(font
					(size 1.27 1.27)
				)
				(justify left bottom)
				(hide yes)
			)
		)
		(pin "2"
		)
		(pin "1"
		)
		(instances
			(project "OCuLink to 10GbE adapter"
				(path ""
					(reference "C203")
					(unit 1)
				)
				(path ""
					(reference "C201")
					(unit 1)
				)
			)
		)
	)
	(symbol
		(lib_id "antmicroCapacitors0402:C_100n_0402")
		(at 187.96 157.48 90)
		(unit 1)
		(exclude_from_sim no)
		(in_bom yes)
		(on_board yes)
		(dnp no)
		(property "Reference" "C200"
			(at 189.738 153.67 90)
			(effects
				(font
					(size 1.27 1.27)
					(thickness 0.15)
				)
				(justify right)
			)
		)
		(property "Value" "C_100n_0402"
			(at 198.12 137.16 0)
			(effects
				(font
					(size 1.27 1.27)
					(thickness 0.15)
				)
				(justify left bottom)
				(hide yes)
			)
		)
		(property "Footprint" "antmicro-footprints:C_0402_1005Metric"
			(at 200.66 137.16 0)
			(effects
				(font
					(size 1.27 1.27)
					(thickness 0.15)
				)
				(justify left bottom)
				(hide yes)
			)
		)
		(property "Datasheet" "https://www.murata.com/products/productdetail?partno=GRM155R61H104KE14%23"
			(at 203.2 137.16 0)
			(effects
				(font
					(size 1.27 1.27)
					(thickness 0.15)
				)
				(justify left bottom)
				(hide yes)
			)
		)
		(property "Description" "SMD Multilayer Ceramic Capacitor, 0.1 µF, 50 V, 0402 [1005 Metric], ± 10%, X5R, GRM Series"
			(at 187.96 157.48 0)
			(effects
				(font
					(size 1.27 1.27)
				)
				(hide yes)
			)
		)
		(property "MPN" "GRM155R61H104KE14D"
			(at 205.74 137.16 0)
			(effects
				(font
					(size 1.27 1.27)
					(thickness 0.15)
				)
				(justify left bottom)
				(hide yes)
			)
		)
		(property "Manufacturer" "Murata"
			(at 208.28 137.16 0)
			(effects
				(font
					(size 1.27 1.27)
					(thickness 0.15)
				)
				(justify left bottom)
				(hide yes)
			)
		)
		(property "License" "Apache-2.0"
			(at 210.82 137.16 0)
			(effects
				(font
					(size 1.27 1.27)
					(thickness 0.15)
				)
				(justify left bottom)
				(hide yes)
			)
		)
		(property "Author" "Antmicro"
			(at 213.36 137.16 0)
			(effects
				(font
					(size 1.27 1.27)
					(thickness 0.15)
				)
				(justify left bottom)
				(hide yes)
			)
		)
		(property "Val" "100n"
			(at 189.738 156.21 90)
			(effects
				(font
					(size 1.27 1.27)
					(thickness 0.15)
				)
				(justify right)
			)
		)
		(property "Voltage" "50V"
			(at 215.9 137.16 0)
			(effects
				(font
					(size 1.27 1.27)
				)
				(justify left bottom)
				(hide yes)
			)
		)
		(property "Dielectric" "X5R"
			(at 218.44 137.16 0)
			(effects
				(font
					(size 1.27 1.27)
				)
				(justify left bottom)
				(hide yes)
			)
		)
		(pin "2"
		)
		(pin "1"
		)
		(instances
			(project "OCuLink to 10GbE adapter"
				(path ""
					(reference "C202")
					(unit 1)
				)
				(path ""
					(reference "C200")
					(unit 1)
				)
			)
		)
	)
	(symbol
		(lib_id "antmicropower:GND")
		(at 196.85 162.56 0)
		(unit 1)
		(exclude_from_sim no)
		(in_bom yes)
		(on_board yes)
		(dnp no)
		(fields_autoplaced yes)
		(property "Reference" "#PWR0328"
			(at 196.85 168.91 0)
			(effects
				(font
					(size 1.27 1.27)
				)
				(hide yes)
			)
		)
		(property "Value" "GND"
			(at 194.945 167.005 0)
			(effects
				(font
					(size 1.27 1.27)
					(thickness 0.15)
				)
				(justify left bottom)
			)
		)
		(property "Footprint" ""
			(at 205.74 170.18 0)
			(effects
				(font
					(size 1.27 1.27)
					(thickness 0.15)
				)
				(justify left bottom)
				(hide yes)
			)
		)
		(property "Datasheet" ""
			(at 205.74 175.26 0)
			(effects
				(font
					(size 1.27 1.27)
					(thickness 0.15)
				)
				(justify left bottom)
				(hide yes)
			)
		)
		(property "Description" ""
			(at 196.85 162.56 0)
			(effects
				(font
					(size 1.27 1.27)
				)
			)
		)
		(property "Author" "Antmicro"
			(at 205.74 167.64 0)
			(effects
				(font
					(size 1.27 1.27)
					(thickness 0.15)
				)
				(justify left bottom)
				(hide yes)
			)
		)
		(property "License" "Apache-2.0"
			(at 205.74 170.18 0)
			(effects
				(font
					(size 1.27 1.27)
					(thickness 0.15)
				)
				(justify left bottom)
				(hide yes)
			)
		)
		(pin "1"
		)
		(instances
			(project "OCuLink to 10GbE adapter"
				(path ""
					(reference "#PWR0330")
					(unit 1)
				)
				(path ""
					(reference "#PWR0328")
					(unit 1)
				)
			)
		)
	)
	(symbol
		(lib_id "antmicropower:GND")
		(at 226.06 162.56 0)
		(unit 1)
		(exclude_from_sim no)
		(in_bom yes)
		(on_board yes)
		(dnp no)
		(fields_autoplaced yes)
		(property "Reference" "#PWR0329"
			(at 226.06 168.91 0)
			(effects
				(font
					(size 1.27 1.27)
				)
				(hide yes)
			)
		)
		(property "Value" "GND"
			(at 224.155 167.005 0)
			(effects
				(font
					(size 1.27 1.27)
					(thickness 0.15)
				)
				(justify left bottom)
			)
		)
		(property "Footprint" ""
			(at 234.95 170.18 0)
			(effects
				(font
					(size 1.27 1.27)
					(thickness 0.15)
				)
				(justify left bottom)
				(hide yes)
			)
		)
		(property "Datasheet" ""
			(at 234.95 175.26 0)
			(effects
				(font
					(size 1.27 1.27)
					(thickness 0.15)
				)
				(justify left bottom)
				(hide yes)
			)
		)
		(property "Description" ""
			(at 226.06 162.56 0)
			(effects
				(font
					(size 1.27 1.27)
				)
			)
		)
		(property "Author" "Antmicro"
			(at 234.95 167.64 0)
			(effects
				(font
					(size 1.27 1.27)
					(thickness 0.15)
				)
				(justify left bottom)
				(hide yes)
			)
		)
		(property "License" "Apache-2.0"
			(at 234.95 170.18 0)
			(effects
				(font
					(size 1.27 1.27)
					(thickness 0.15)
				)
				(justify left bottom)
				(hide yes)
			)
		)
		(pin "1"
		)
		(instances
			(project "OCuLink to 10GbE adapter"
				(path ""
					(reference "#PWR0331")
					(unit 1)
				)
				(path ""
					(reference "#PWR0329")
					(unit 1)
				)
			)
		)
	)
	(symbol
		(lib_id "antmicroPMICORControllersIdealDiodes:LTC4412IS6")
		(at 199.39 149.86 0)
		(unit 1)
		(exclude_from_sim no)
		(in_bom yes)
		(on_board yes)
		(dnp no)
		(property "Reference" "U11"
			(at 208.28 143.256 0)
			(effects
				(font
					(size 1.27 1.27)
					(thickness 0.15)
				)
			)
		)
		(property "Value" "LTC4412IS6"
			(at 231.14 154.94 0)
			(effects
				(font
					(size 1.27 1.27)
					(thickness 0.15)
				)
				(justify left bottom)
				(hide yes)
			)
		)
		(property "Footprint" "antmicro-footprints:SOT-23-6"
			(at 231.14 157.48 0)
			(effects
				(font
					(size 1.27 1.27)
					(thickness 0.15)
				)
				(justify left bottom)
				(hide yes)
			)
		)
		(property "Datasheet" "https://www.analog.com/media/en/technical-documentation/data-sheets/4412fb.pdf"
			(at 231.14 160.02 0)
			(effects
				(font
					(size 1.27 1.27)
					(thickness 0.15)
				)
				(justify left bottom)
				(hide yes)
			)
		)
		(property "Description" "Ideal diode controller"
			(at 199.39 149.86 0)
			(effects
				(font
					(size 1.27 1.27)
				)
				(hide yes)
			)
		)
		(property "MPN" "LTC4412IS6#TRMPBF"
			(at 208.28 145.796 0)
			(effects
				(font
					(size 1.27 1.27)
					(thickness 0.15)
				)
			)
		)
		(property "Manufacturer" "Analog Devices"
			(at 231.14 165.1 0)
			(effects
				(font
					(size 1.27 1.27)
					(thickness 0.15)
				)
				(justify left bottom)
				(hide yes)
			)
		)
		(property "Author" "Antmicro"
			(at 231.14 167.64 0)
			(effects
				(font
					(size 1.27 1.27)
					(thickness 0.15)
				)
				(justify left bottom)
				(hide yes)
			)
		)
		(property "License" "Apache-2.0"
			(at 231.14 170.18 0)
			(effects
				(font
					(size 1.27 1.27)
					(thickness 0.15)
				)
				(justify left bottom)
				(hide yes)
			)
		)
		(pin "6"
		)
		(pin "5"
		)
		(pin "4"
		)
		(pin "1"
		)
		(pin "3"
		)
		(pin "2"
		)
		(instances
			(project "OCuLink to 10GbE adapter"
				(path ""
					(reference "U12")
					(unit 1)
				)
				(path ""
					(reference "U11")
					(unit 1)
				)
			)
		)
	)
	(symbol
		(lib_id "antmicroTransistorsFETsMOSFETsSingle:SQS401EN-T1_BE3")
		(at 219.71 143.51 90)
		(unit 1)
		(exclude_from_sim no)
		(in_bom yes)
		(on_board yes)
		(dnp no)
		(property "Reference" "Q2"
			(at 217.17 130.81 90)
			(effects
				(font
					(size 1.27 1.27)
					(thickness 0.15)
				)
			)
		)
		(property "Value" "SQS401EN-T1_BE3"
			(at 229.87 128.27 0)
			(effects
				(font
					(size 1.27 1.27)
					(thickness 0.15)
				)
				(justify left bottom)
				(hide yes)
			)
		)
		(property "Footprint" "antmicro-footprints:Vishay_PowerPAK_1212-8_Single"
			(at 232.41 128.27 0)
			(effects
				(font
					(size 1.27 1.27)
					(thickness 0.15)
				)
				(justify left bottom)
				(hide yes)
			)
		)
		(property "Datasheet" "https://www.vishay.com/docs/65529/sqs401en.pdf"
			(at 234.95 128.27 0)
			(effects
				(font
					(size 1.27 1.27)
					(thickness 0.15)
				)
				(justify left bottom)
				(hide yes)
			)
		)
		(property "Description" "MOSFET, P Channel, 40 V, 16A, 0.047 ohm, PowerPAK 1212-8, Surface Mount"
			(at 219.71 143.51 0)
			(effects
				(font
					(size 1.27 1.27)
				)
				(hide yes)
			)
		)
		(property "MPN" "SQS401EN-T1_BE3"
			(at 217.17 133.35 90)
			(effects
				(font
					(size 1.27 1.27)
					(thickness 0.15)
				)
			)
		)
		(property "Manufacturer" "Vishay"
			(at 237.49 128.27 0)
			(effects
				(font
					(size 1.27 1.27)
					(thickness 0.15)
				)
				(justify left bottom)
				(hide yes)
			)
		)
		(property "Author" "Antmicro"
			(at 240.03 128.27 0)
			(effects
				(font
					(size 1.27 1.27)
					(thickness 0.15)
				)
				(justify left bottom)
				(hide yes)
			)
		)
		(property "License" "Apache-2.0"
			(at 242.57 128.27 0)
			(effects
				(font
					(size 1.27 1.27)
					(thickness 0.15)
				)
				(justify left bottom)
				(hide yes)
			)
		)
		(pin "4"
		)
		(pin "1"
		)
		(pin "3"
		)
		(pin "5"
		)
		(pin "2"
		)
		(instances
			(project "OCuLink to 10GbE adapter"
				(path ""
					(reference "Q3")
					(unit 1)
				)
				(path ""
					(reference "Q2")
					(unit 1)
				)
			)
		)
	)
)
